# S9S_MB_2U (Grand Teton) — schematic netlist excerpt (pin names and nets, part order shuffled) for the footprints in the layout excerpt that follows; sources: Cadence DE-HDL packaged netlist, KiCad conversion of 03242023_DA0F0TMBIJ0_F0T_Motherboard_J_brd_V01_OCP.brd

U193  MAX11617EEET  MAX11617EEE+T EMPTY  pkg QSOP16_0-635_4-9X3-89  page 250
  \ain11||ref\  = MAX11617_VREF_R
  AIN10  = GND
  AIN9  = GND
  AIN8  = GND
  AIN0  = P12V_AUX_ADC_MAM
  AIN1  = P12V_OCP_SFF_ISENSE_MAM
  AIN2  = P12V_OCP_V3_2_ISENSE_MAM
  AIN3  = P5V_ADC_MAM
  AIN4  = P3V3_ADC_MAM
  AIN5  = P3V3_AUX_ADC_MAM
  AIN6  = P3V3_PDB_AUX_ADC_MAM
  AIN7  = P12V_E1S_0_ISENSE_MAM
  SCL  = SMB_SEN_MAM_3V3AUX_SCL
  SDA  = SMB_SEN_MAM_3V3AUX_SDA
  GND  = GND
  VDD  = P3V3_MAX11617_VDD

R3428  Q_RES  100K 1% EMPTY  pkg 0402LF  page 147 : A = GPU_FPGA_THERM_OVERT_N ; B = GND

(kicad_pcb
	(version 20260206)
	(generator "pcbnew")
	(generator_version "10.0")
	(general
		(thickness 1.6)
		(legacy_teardrops no)
	)
	(paper "A4")
	(title_block
		(title "03242023_DA0F0TMBIJ0_F0T_Motherboard_J_brd_V01_OCP.brd")
		(comment 1 "Grand Teton / footprints 407-408 of 6105")
	)
	(layers
		(0 "F.Cu" signal "TOP")
		(4 "In1.Cu" signal "GND")
		(6 "In2.Cu" signal "IN1")
		(8 "In3.Cu" signal "GND1")
		(10 "In4.Cu" signal "IN2")
		(12 "In5.Cu" signal "GND2")
		(14 "In6.Cu" signal "IN3")
		(16 "In7.Cu" signal "GND3")
		(18 "In8.Cu" signal "VCC")
		(20 "In9.Cu" signal "VCC1")
		(22 "In10.Cu" signal "GND4")
		(24 "In11.Cu" signal "IN4")
		(26 "In12.Cu" signal "GND5")
		(28 "In13.Cu" signal "IN5")
		(30 "In14.Cu" signal "GND6")
		(32 "In15.Cu" signal "IN6")
		(34 "In16.Cu" signal "GND7")
		(2 "B.Cu" signal "BOTTOM")
		(9 "F.Adhes" user "F.Adhesive")
		(11 "B.Adhes" user "B.Adhesive")
		(13 "F.Paste" user "Package Geometry/Pastemask Top")
		(15 "B.Paste" user "Package Geometry/Pastemask Bottom")
		(5 "F.SilkS" user "Ref Des/Silkscreen Top")
		(7 "B.SilkS" user "Ref Des/Silkscreen Bottom")
		(1 "F.Mask" user "Board Geometry/Soldermask Top")
		(3 "B.Mask" user "Board Geometry/Soldermask Bottom")
		(17 "Dwgs.User" user "User.Drawings")
		(19 "Cmts.User" user "User.Comments")
		(21 "Eco1.User" user "User.Eco1")
		(23 "Eco2.User" user "User.Eco2")
		(25 "Edge.Cuts" user "Board Geometry/Outline")
		(27 "Margin" user)
		(31 "F.CrtYd" user "Package Geometry/Place Bound Top")
		(29 "B.CrtYd" user "Package Geometry/Place Bound Bottom")
		(35 "F.Fab" user "Ref Des/Assembly Top")
		(33 "B.Fab" user "Ref Des/Assembly Bottom")
	)
	(footprint ""
		(layer "F.Cu")
		(at 24.069802 -407.890218 180)
		(property "Reference" "R3428"
			(at 0 0 180)
			(layer "F.SilkS")
			(hide yes)
			(effects
				(font
					(size 1.27 1.27)
				)
			)
		)
		(property "Value" ""
			(at 0 0 180)
			(layer "F.Fab")
			(effects
				(font
					(size 1.27 1.27)
				)
			)
		)
		(duplicate_pad_numbers_are_jumpers no)
		(fp_line
			(start 0.7874 0.4064)
			(end -0.7874 0.4064)
			(stroke
				(width 0.1524)
				(type default)
			)
			(layer "F.SilkS")
		)
		(fp_line
			(start 0.7874 -0.4064)
			(end 0.7874 0.4064)
			(stroke
				(width 0.1524)
				(type default)
			)
			(layer "F.SilkS")
		)
		(fp_line
			(start -0.7874 0.4064)
			(end -0.7874 -0.4064)
			(stroke
				(width 0.1524)
				(type default)
			)
			(layer "F.SilkS")
		)
		(fp_line
			(start -0.7874 -0.4064)
			(end 0.7874 -0.4064)
			(stroke
				(width 0.1524)
				(type default)
			)
			(layer "F.SilkS")
		)
		(fp_line
			(start 0.67945 0.3048)
			(end 0.120396 0.3048)
			(stroke
				(width 0.1)
				(type default)
			)
			(layer "F.Fab")
		)
		(fp_line
			(start 0.67945 -0.3048)
			(end 0.67945 0.3048)
			(stroke
				(width 0.1)
				(type default)
			)
			(layer "F.Fab")
		)
		(fp_line
			(start 0.12065 -0.2794)
			(end 0.12065 -0.3048)
			(stroke
				(width 0.1)
				(type default)
			)
			(layer "F.Fab")
		)
		(fp_line
			(start 0.12065 -0.3048)
			(end 0.67945 -0.3048)
			(stroke
				(width 0.1)
				(type default)
			)
			(layer "F.Fab")
		)
		(fp_line
			(start 0.120396 0.3048)
			(end 0.120396 0.2794)
			(stroke
				(width 0.1)
				(type default)
			)
			(layer "F.Fab")
		)
		(fp_line
			(start 0.120396 0.2794)
			(end -0.12065 0.2794)
			(stroke
				(width 0.1)
				(type default)
			)
			(layer "F.Fab")
		)
		(fp_line
			(start -0.12065 0.3048)
			(end -0.67945 0.3048)
			(stroke
				(width 0.1)
				(type default)
			)
			(layer "F.Fab")
		)
		(fp_line
			(start -0.12065 0.2794)
			(end -0.12065 0.3048)
			(stroke
				(width 0.1)
				(type default)
			)
			(layer "F.Fab")
		)
		(fp_line
			(start -0.12065 -0.2794)
			(end 0.12065 -0.2794)
			(stroke
				(width 0.1)
				(type default)
			)
			(layer "F.Fab")
		)
		(fp_line
			(start -0.12065 -0.305054)
			(end -0.12065 -0.2794)
			(stroke
				(width 0.1)
				(type default)
			)
			(layer "F.Fab")
		)
		(fp_line
			(start -0.67945 0.3048)
			(end -0.67945 -0.305054)
			(stroke
				(width 0.1)
				(type default)
			)
			(layer "F.Fab")
		)
		(fp_line
			(start -0.67945 -0.305054)
			(end -0.12065 -0.305054)
			(stroke
				(width 0.1)
				(type default)
			)
			(layer "F.Fab")
		)
		(pad "1" smd circle
			(at -0.40005 0 180)
			(size 0 0)
			(layers "F.Cu" "F.Mask" "F.Paste")
			(net "GPU_FPGA_THERM_OVERT_N")
		)
		(pad "2" smd circle
			(at 0.40005 0 180)
			(size 0 0)
			(layers "F.Cu" "F.Mask" "F.Paste")
			(net "GND")
		)
	)
	(footprint ""
		(layer "F.Cu")
		(at 39.643558 -100.49129)
		(property "Reference" "U193"
			(at -1.797558 3.525012 0)
			(unlocked yes)
			(layer "F.SilkS")
			(effects
				(font
					(size 0.7874 0.5842)
					(thickness 0.1524)
				)
				(justify left)
			)
		)
		(property "Value" ""
			(at 0 0 0)
			(layer "F.Fab")
			(effects
				(font
					(size 1.27 1.27)
				)
			)
		)
		(duplicate_pad_numbers_are_jumpers no)
		(fp_line
			(start -1.715516 -2.489962)
			(end -1.715516 2.489962)
			(stroke
				(width 0.1524)
				(type default)
			)
			(layer "F.SilkS")
		)
		(fp_line
			(start -1.715516 2.489962)
			(end 1.715516 2.489962)
			(stroke
				(width 0.1524)
				(type default)
			)
			(layer "F.SilkS")
		)
		(fp_line
			(start -1.092962 -2.489962)
			(end -1.715516 -2.489962)
			(stroke
				(width 0.1524)
				(type default)
			)
			(layer "F.SilkS")
		)
		(fp_line
			(start 0 -1.397)
			(end -1.092962 -2.489962)
			(stroke
				(width 0.1524)
				(type default)
			)
			(layer "F.SilkS")
		)
		(fp_line
			(start 1.092962 -2.489962)
			(end 0 -1.397)
			(stroke
				(width 0.1524)
				(type default)
			)
			(layer "F.SilkS")
		)
		(fp_line
			(start 1.715516 -2.489962)
			(end 1.092962 -2.489962)
			(stroke
				(width 0.1524)
				(type default)
			)
			(layer "F.SilkS")
		)
		(fp_line
			(start 1.715516 2.489962)
			(end 1.715516 -2.489962)
			(stroke
				(width 0.1524)
				(type default)
			)
			(layer "F.SilkS")
		)
		(fp_poly
			(pts
				(xy -2.187956 -3.79984) (xy -2.695956 -2.78384) (xy -3.203956 -3.79984)
			)
			(stroke
				(width 0)
				(type default)
			)
			(fill yes)
			(layer "F.SilkS")
		)
		(fp_line
			(start -1.994916 -2.489962)
			(end -1.994916 2.489962)
			(stroke
				(width 0.1)
				(type default)
			)
			(layer "F.Fab")
		)
		(fp_line
			(start -1.994916 2.489962)
			(end 1.994916 2.489962)
			(stroke
				(width 0.1)
				(type default)
			)
			(layer "F.Fab")
		)
		(fp_line
			(start 1.994916 -2.489962)
			(end -1.994916 -2.489962)
			(stroke
				(width 0.1)
				(type default)
			)
			(layer "F.Fab")
		)
		(fp_line
			(start 1.994916 2.489962)
			(end 1.994916 -2.489962)
			(stroke
				(width 0.1)
				(type default)
			)
			(layer "F.Fab")
		)
		(fp_poly
			(pts
				(xy -4.699 -2.7305) (xy -4.699 -1.7145) (xy -3.683 -2.2225)
			)
			(stroke
				(width 0)
				(type default)
			)
			(fill yes)
			(layer "F.Fab")
		)
		(pad "1" smd rect
			(at -2.655062 -2.2225 90)
			(size 0.381 1.6002)
			(layers "F.Cu" "F.Mask" "F.Paste")
			(net "MAX11617_VREF_R")
		)
		(pad "2" smd rect
			(at -2.655062 -1.5875 90)
			(size 0.381 1.6002)
			(layers "F.Cu" "F.Mask" "F.Paste")
			(net "GND")
		)
		(pad "3" smd rect
			(at -2.655062 -0.9525 90)
			(size 0.381 1.6002)
			(layers "F.Cu" "F.Mask" "F.Paste")
			(net "GND")
		)
		(pad "4" smd rect
			(at -2.655062 -0.3175 90)
			(size 0.381 1.6002)
			(layers "F.Cu" "F.Mask" "F.Paste")
			(net "GND")
		)
		(pad "5" smd rect
			(at -2.655062 0.3175 90)
			(size 0.381 1.6002)
			(layers "F.Cu" "F.Mask" "F.Paste")
			(net "P12V_AUX_ADC_MAM")
		)
		(pad "6" smd rect
			(at -2.655062 0.9525 90)
			(size 0.381 1.6002)
			(layers "F.Cu" "F.Mask" "F.Paste")
			(net "P12V_OCP_SFF_ISENSE_MAM")
		)
		(pad "7" smd rect
			(at -2.655062 1.5875 90)
			(size 0.381 1.6002)
			(layers "F.Cu" "F.Mask" "F.Paste")
			(net "P12V_OCP_V3_2_ISENSE_MAM")
		)
		(pad "8" smd rect
			(at -2.655062 2.2225 90)
			(size 0.381 1.6002)
			(layers "F.Cu" "F.Mask" "F.Paste")
			(net "P5V_ADC_MAM")
		)
		(pad "9" smd rect
			(at 2.655062 2.2225 90)
			(size 0.381 1.6002)
			(layers "F.Cu" "F.Mask" "F.Paste")
			(net "P3V3_ADC_MAM")
		)
		(pad "10" smd rect
			(at 2.655062 1.5875 90)
			(size 0.381 1.6002)
			(layers "F.Cu" "F.Mask" "F.Paste")
			(net "P3V3_AUX_ADC_MAM")
		)
		(pad "11" smd rect
			(at 2.655062 0.9525 90)
			(size 0.381 1.6002)
			(layers "F.Cu" "F.Mask" "F.Paste")
			(net "P3V3_PDB_AUX_ADC_MAM")
		)
		(pad "12" smd rect
			(at 2.655062 0.3175 90)
			(size 0.381 1.6002)
			(layers "F.Cu" "F.Mask" "F.Paste")
			(net "P12V_E1S_0_ISENSE_MAM")
		)
		(pad "13" smd rect
			(at 2.655062 -0.3175 90)
			(size 0.381 1.6002)
			(layers "F.Cu" "F.Mask" "F.Paste")
			(net "SMB_SEN_MAM_3V3AUX_SCL")
		)
		(pad "14" smd rect
			(at 2.655062 -0.9525 90)
			(size 0.381 1.6002)
			(layers "F.Cu" "F.Mask" "F.Paste")
			(net "SMB_SEN_MAM_3V3AUX_SDA")
		)
		(pad "15" smd rect
			(at 2.655062 -1.5875 90)
			(size 0.381 1.6002)
			(layers "F.Cu" "F.Mask" "F.Paste")
			(net "GND")
		)
		(pad "16" smd rect
			(at 2.655062 -2.2225 90)
			(size 0.381 1.6002)
			(layers "F.Cu" "F.Mask" "F.Paste")
			(net "P3V3_MAX11617_VDD")
		)
	)
)
